(kicad_pcb
	(version 20260206)
	(generator "pcbnew")
	(generator_version "10.0")
	(general
		(thickness 1.6)
		(legacy_teardrops no)
	)
	(paper "A4")
	(title_block
		(title "9052_F0T_PDB_Converter_Brick_F_V03_1208_1600_OCP.brd")
		(comment 1 "Grand Teton / footprints 53-61 of 578")
	)
	(layers
		(0 "F.Cu" signal "TOP")
		(4 "In1.Cu" signal "GND")
		(6 "In2.Cu" signal "IN1")
		(8 "In3.Cu" signal "GND1")
		(10 "In4.Cu" signal "VCC")
		(12 "In5.Cu" signal "VCC1")
		(14 "In6.Cu" signal "GND2")
		(16 "In7.Cu" signal "IN2")
		(18 "In8.Cu" signal "GND3")
		(2 "B.Cu" signal "BOTTOM")
		(9 "F.Adhes" user "F.Adhesive")
		(11 "B.Adhes" user "B.Adhesive")
		(13 "F.Paste" user "Package Geometry/Pastemask Top")
		(15 "B.Paste" user "Package Geometry/Pastemask Bottom")
		(5 "F.SilkS" user "Ref Des/Silkscreen Top")
		(7 "B.SilkS" user "Ref Des/Silkscreen Bottom")
		(1 "F.Mask" user "Board Geometry/Soldermask Top")
		(3 "B.Mask" user "Board Geometry/Soldermask Bottom")
		(17 "Dwgs.User" user "User.Drawings")
		(19 "Cmts.User" user "User.Comments")
		(21 "Eco1.User" user "User.Eco1")
		(23 "Eco2.User" user "User.Eco2")
		(25 "Edge.Cuts" user "Board Geometry/Outline")
		(27 "Margin" user)
		(31 "F.CrtYd" user "Package Geometry/Place Bound Top")
		(29 "B.CrtYd" user "Package Geometry/Place Bound Bottom")
		(35 "F.Fab" user "Ref Des/Assembly Top")
		(33 "B.Fab" user "Ref Des/Assembly Bottom")
	)
	(footprint ""
		(layer "F.Cu")
		(at 278.003 -44.069 180)
		(property "Reference" "PR20"
			(at 0 0 180)
			(layer "F.SilkS")
			(hide yes)
			(effects
				(font
					(size 1.27 1.27)
				)
			)
		)
		(property "Value" ""
			(at 0 0 180)
			(layer "F.Fab")
			(effects
				(font
					(size 1.27 1.27)
				)
			)
		)
		(duplicate_pad_numbers_are_jumpers no)
		(fp_line
			(start 0.7874 0.4064)
			(end -0.7874 0.4064)
			(stroke
				(width 0.1524)
				(type default)
			)
			(layer "F.SilkS")
		)
		(fp_line
			(start 0.7874 -0.4064)
			(end 0.7874 0.4064)
			(stroke
				(width 0.1524)
				(type default)
			)
			(layer "F.SilkS")
		)
		(fp_line
			(start -0.7874 0.4064)
			(end -0.7874 -0.4064)
			(stroke
				(width 0.1524)
				(type default)
			)
			(layer "F.SilkS")
		)
		(fp_line
			(start -0.7874 -0.4064)
			(end 0.7874 -0.4064)
			(stroke
				(width 0.1524)
				(type default)
			)
			(layer "F.SilkS")
		)
		(fp_line
			(start 0.67945 0.3048)
			(end 0.120396 0.3048)
			(stroke
				(width 0.1)
				(type default)
			)
			(layer "F.Fab")
		)
		(fp_line
			(start 0.67945 -0.3048)
			(end 0.67945 0.3048)
			(stroke
				(width 0.1)
				(type default)
			)
			(layer "F.Fab")
		)
		(fp_line
			(start 0.12065 -0.2794)
			(end 0.12065 -0.3048)
			(stroke
				(width 0.1)
				(type default)
			)
			(layer "F.Fab")
		)
		(fp_line
			(start 0.12065 -0.3048)
			(end 0.67945 -0.3048)
			(stroke
				(width 0.1)
				(type default)
			)
			(layer "F.Fab")
		)
		(fp_line
			(start 0.120396 0.3048)
			(end 0.120396 0.2794)
			(stroke
				(width 0.1)
				(type default)
			)
			(layer "F.Fab")
		)
		(fp_line
			(start 0.120396 0.2794)
			(end -0.12065 0.2794)
			(stroke
				(width 0.1)
				(type default)
			)
			(layer "F.Fab")
		)
		(fp_line
			(start -0.12065 0.3048)
			(end -0.67945 0.3048)
			(stroke
				(width 0.1)
				(type default)
			)
			(layer "F.Fab")
		)
		(fp_line
			(start -0.12065 0.2794)
			(end -0.12065 0.3048)
			(stroke
				(width 0.1)
				(type default)
			)
			(layer "F.Fab")
		)
		(fp_line
			(start -0.12065 -0.2794)
			(end 0.12065 -0.2794)
			(stroke
				(width 0.1)
				(type default)
			)
			(layer "F.Fab")
		)
		(fp_line
			(start -0.12065 -0.305054)
			(end -0.12065 -0.2794)
			(stroke
				(width 0.1)
				(type default)
			)
			(layer "F.Fab")
		)
		(fp_line
			(start -0.67945 0.3048)
			(end -0.67945 -0.305054)
			(stroke
				(width 0.1)
				(type default)
			)
			(layer "F.Fab")
		)
		(fp_line
			(start -0.67945 -0.305054)
			(end -0.12065 -0.305054)
			(stroke
				(width 0.1)
				(type default)
			)
			(layer "F.Fab")
		)
		(pad "1" smd circle
			(at -0.40005 0 180)
			(size 0 0)
			(layers "F.Cu" "F.Mask" "F.Paste")
			(net "P52V_HS1_ISTART")
		)
		(pad "2" smd circle
			(at 0.40005 0 180)
			(size 0 0)
			(layers "F.Cu" "F.Mask" "F.Paste")
			(net "GND_FIELD_SIGNAL")
		)
	)
	(footprint ""
		(layer "F.Cu")
		(at 291.74059 -31.727902)
		(property "Reference" "PJ1"
			(at -2.18059 -1.011428 0)
			(unlocked yes)
			(layer "F.SilkS")
			(effects
				(font
					(size 0.7874 0.5842)
					(thickness 0.1524)
				)
				(justify left)
			)
		)
		(property "Value" ""
			(at 0 0 0)
			(layer "F.Fab")
			(effects
				(font
					(size 1.27 1.27)
				)
			)
		)
		(duplicate_pad_numbers_are_jumpers no)
		(pad "1" smd circle
			(at -0.7493 0 90)
			(size 0 0)
			(layers "F.Cu" "F.Mask" "F.Paste")
			(net "GND_FIELD_SIGNAL")
		)
		(pad "2" smd rect
			(at 0.7493 0 270)
			(size 0.7112 0.8128)
			(layers "F.Cu" "F.Mask" "F.Paste")
			(net "GND")
		)
		(zone
			(layer "F.Cu")
			(hatch none 0.5)
			(connect_pads
				(clearance 0)
			)
			(min_thickness 0.25)
			(keepout
				(tracks allowed)
				(vias not_allowed)
				(pads allowed)
				(copperpour not_allowed)
				(footprints allowed)
			)
			(placement
				(enabled no)
				(sheetname "")
			)
			(fill
				(thermal_gap 0.5)
				(thermal_bridge_width 0.5)
				(island_removal_mode 0)
			)
			(polygon
				(pts
					(xy 292.94709 -32.134302) (xy 290.55949 -32.134302) (xy 290.55949 -31.316676) (xy 292.94709 -31.316676)
				)
			)
		)
	)
	(footprint ""
		(layer "F.Cu")
		(at 170.053 -12.4968 90)
		(property "Reference" "PC566"
			(at 0 0 90)
			(layer "F.SilkS")
			(hide yes)
			(effects
				(font
					(size 1.27 1.27)
				)
			)
		)
		(property "Value" ""
			(at 0 0 90)
			(layer "F.Fab")
			(effects
				(font
					(size 1.27 1.27)
				)
			)
		)
		(duplicate_pad_numbers_are_jumpers no)
		(fp_line
			(start 1.524 -0.762)
			(end 1.524 0.762)
			(stroke
				(width 0.1524)
				(type default)
			)
			(layer "F.SilkS")
		)
		(fp_line
			(start -1.524 -0.762)
			(end 1.524 -0.762)
			(stroke
				(width 0.1524)
				(type default)
			)
			(layer "F.SilkS")
		)
		(fp_line
			(start 1.524 0.762)
			(end -1.524 0.762)
			(stroke
				(width 0.1524)
				(type default)
			)
			(layer "F.SilkS")
		)
		(fp_line
			(start -1.524 0.762)
			(end -1.524 -0.762)
			(stroke
				(width 0.1524)
				(type default)
			)
			(layer "F.SilkS")
		)
		(fp_line
			(start 1.1049 -0.724916)
			(end -1.1049 -0.724916)
			(stroke
				(width 0.1)
				(type default)
			)
			(layer "F.Fab")
		)
		(fp_line
			(start -1.1049 -0.724916)
			(end -1.1049 0.724916)
			(stroke
				(width 0.1)
				(type default)
			)
			(layer "F.Fab")
		)
		(fp_line
			(start 1.1049 0.724916)
			(end 1.1049 -0.724916)
			(stroke
				(width 0.1)
				(type default)
			)
			(layer "F.Fab")
		)
		(fp_line
			(start -1.1049 0.724916)
			(end 1.1049 0.724916)
			(stroke
				(width 0.1)
				(type default)
			)
			(layer "F.Fab")
		)
		(pad "1" smd rect
			(at -0.889 0 270)
			(size 1.016 1.27)
			(layers "F.Cu" "F.Mask" "F.Paste")
			(net "SW_P12V_FILT__P3V3_AUX")
		)
		(pad "2" smd rect
			(at 0.889 0 270)
			(size 1.016 1.27)
			(layers "F.Cu" "F.Mask" "F.Paste")
			(net "GND")
		)
	)
	(footprint ""
		(layer "F.Cu")
		(at 96.905826 -127.889)
		(property "Reference" "PC49"
			(at 0 0 0)
			(layer "F.SilkS")
			(hide yes)
			(effects
				(font
					(size 1.27 1.27)
				)
			)
		)
		(property "Value" ""
			(at 0 0 0)
			(layer "F.Fab")
			(effects
				(font
					(size 1.27 1.27)
				)
			)
		)
		(duplicate_pad_numbers_are_jumpers no)
		(fp_line
			(start -2.2098 -0.9398)
			(end 2.2098 -0.9398)
			(stroke
				(width 0.1524)
				(type default)
			)
			(layer "F.SilkS")
		)
		(fp_line
			(start -2.2098 0.9398)
			(end -2.2098 -0.9398)
			(stroke
				(width 0.1524)
				(type default)
			)
			(layer "F.SilkS")
		)
		(fp_line
			(start 2.2098 -0.9398)
			(end 2.2098 0.9398)
			(stroke
				(width 0.1524)
				(type default)
			)
			(layer "F.SilkS")
		)
		(fp_line
			(start 2.2098 0.9398)
			(end -2.2098 0.9398)
			(stroke
				(width 0.1524)
				(type default)
			)
			(layer "F.SilkS")
		)
		(fp_line
			(start -1.700022 -0.899922)
			(end 1.700022 -0.899922)
			(stroke
				(width 0.1)
				(type default)
			)
			(layer "F.Fab")
		)
		(fp_line
			(start -1.700022 0.899922)
			(end -1.700022 -0.899922)
			(stroke
				(width 0.1)
				(type default)
			)
			(layer "F.Fab")
		)
		(fp_line
			(start 1.700022 -0.899922)
			(end 1.700022 0.899922)
			(stroke
				(width 0.1)
				(type default)
			)
			(layer "F.Fab")
		)
		(fp_line
			(start 1.700022 0.899922)
			(end -1.700022 0.899922)
			(stroke
				(width 0.1)
				(type default)
			)
			(layer "F.Fab")
		)
		(pad "1" smd rect
			(at -1.4732 0 180)
			(size 1.1684 1.5748)
			(layers "F.Cu" "F.Mask" "F.Paste")
			(net "P52V_HS_FILTER")
		)
		(pad "2" smd rect
			(at 1.4732 0 180)
			(size 1.1684 1.5748)
			(layers "F.Cu" "F.Mask" "F.Paste")
			(net "GND")
		)
	)
	(footprint ""
		(layer "F.Cu")
		(at 162.047174 -136.906 90)
		(property "Reference" "PC115"
			(at 6.19633 0.766826 0)
			(unlocked yes)
			(layer "F.SilkS")
			(effects
				(font
					(size 0.7874 0.5842)
					(thickness 0.1524)
				)
				(justify left)
			)
		)
		(property "Value" ""
			(at 0 0 90)
			(layer "F.Fab")
			(effects
				(font
					(size 1.27 1.27)
				)
			)
		)
		(duplicate_pad_numbers_are_jumpers no)
		(fp_line
			(start 5.2578 2.499868)
			(end -5.2578 2.499868)
			(stroke
				(width 0.1524)
				(type default)
			)
			(layer "F.SilkS")
		)
		(fp_circle
			(center 0 2.500122)
			(end 0 7.758176)
			(stroke
				(width 0.1524)
				(type default)
			)
			(fill no)
			(layer "F.SilkS")
		)
		(fp_poly
			(pts
				(arc
					(start 5.2578 2.499868)
					(mid 0 7.757922)
					(end -5.2578 2.499868)
				)
			)
			(stroke
				(width 0)
				(type default)
			)
			(fill yes)
			(layer "F.SilkS")
		)
		(fp_circle
			(center 0 2.500122)
			(end 0 7.758176)
			(stroke
				(width 0.1)
				(type default)
			)
			(fill no)
			(layer "F.Fab")
		)
		(pad "1" thru_hole rect
			(at 0 0)
			(size 1.5748 1.5748)
			(drill 1.0668)
			(layers "*.Cu" "*.Mask")
			(remove_unused_layers no)
			(net "P52V_HS_FILTER")
			(clearance 0)
			(padstack
				(mode front_inner_back)
				(layer "Inner"
					(shape circle)
					(size 1.5748 1.5748)
					(clearance 0)
				)
				(layer "B.Cu"
					(shape rect)
					(size 1.5748 1.5748)
					(clearance 0)
				)
			)
		)
		(pad "2" thru_hole circle
			(at 0 4.99999)
			(size 1.5748 1.5748)
			(drill 1.0668)
			(layers "*.Cu" "*.Mask")
			(remove_unused_layers no)
			(net "GND")
			(clearance 0)
		)
	)
	(footprint ""
		(layer "F.Cu")
		(at 139.065 -60.325)
		(property "Reference" "PR59"
			(at 0 0 0)
			(layer "F.SilkS")
			(hide yes)
			(effects
				(font
					(size 1.27 1.27)
				)
			)
		)
		(property "Value" ""
			(at 0 0 0)
			(layer "F.Fab")
			(effects
				(font
					(size 1.27 1.27)
				)
			)
		)
		(duplicate_pad_numbers_are_jumpers no)
		(fp_line
			(start -1.651 -0.8382)
			(end 1.651 -0.8382)
			(stroke
				(width 0.1524)
				(type default)
			)
			(layer "F.SilkS")
		)
		(fp_line
			(start -1.651 0.8382)
			(end -1.651 -0.8382)
			(stroke
				(width 0.1524)
				(type default)
			)
			(layer "F.SilkS")
		)
		(fp_line
			(start 1.651 -0.8382)
			(end 1.651 0.8382)
			(stroke
				(width 0.1524)
				(type default)
			)
			(layer "F.SilkS")
		)
		(fp_line
			(start 1.651 0.8382)
			(end -1.651 0.8382)
			(stroke
				(width 0.1524)
				(type default)
			)
			(layer "F.SilkS")
		)
		(fp_line
			(start -1.559814 -0.7366)
			(end -1.559814 0.7366)
			(stroke
				(width 0.1)
				(type default)
			)
			(layer "F.Fab")
		)
		(fp_line
			(start -1.559814 0.7366)
			(end -1.524 0.7366)
			(stroke
				(width 0.1)
				(type default)
			)
			(layer "F.Fab")
		)
		(fp_line
			(start -1.524 -0.7366)
			(end -1.559814 -0.7366)
			(stroke
				(width 0.1)
				(type default)
			)
			(layer "F.Fab")
		)
		(fp_line
			(start -1.524 0.7366)
			(end 1.524 0.7366)
			(stroke
				(width 0.1)
				(type default)
			)
			(layer "F.Fab")
		)
		(fp_line
			(start 1.524 -0.7366)
			(end -1.524 -0.7366)
			(stroke
				(width 0.1)
				(type default)
			)
			(layer "F.Fab")
		)
		(fp_line
			(start 1.524 0.7366)
			(end 1.560576 0.7366)
			(stroke
				(width 0.1)
				(type default)
			)
			(layer "F.Fab")
		)
		(fp_line
			(start 1.560576 -0.7366)
			(end 1.524 -0.7366)
			(stroke
				(width 0.1)
				(type default)
			)
			(layer "F.Fab")
		)
		(fp_line
			(start 1.560576 0.7366)
			(end 1.560576 -0.7366)
			(stroke
				(width 0.1)
				(type default)
			)
			(layer "F.Fab")
		)
		(pad "1" smd rect
			(at -0.94996 0 180)
			(size 1.1176 1.3716)
			(layers "F.Cu" "F.Mask" "F.Paste")
			(net "P12V_BRICK")
		)
		(pad "2" smd rect
			(at 0.94996 0 180)
			(size 1.1176 1.3716)
			(layers "F.Cu" "F.Mask" "F.Paste")
			(net "GND")
		)
	)
	(footprint ""
		(layer "F.Cu")
		(at 222.504 -95.504 -90)
		(property "Reference" "C29"
			(at 0 0 270)
			(layer "F.SilkS")
			(hide yes)
			(effects
				(font
					(size 1.27 1.27)
				)
			)
		)
		(property "Value" ""
			(at 0 0 270)
			(layer "F.Fab")
			(effects
				(font
					(size 1.27 1.27)
				)
			)
		)
		(duplicate_pad_numbers_are_jumpers no)
		(fp_line
			(start -2.2098 0.9398)
			(end -2.2098 -0.9398)
			(stroke
				(width 0.1524)
				(type default)
			)
			(layer "F.SilkS")
		)
		(fp_line
			(start 2.2098 0.9398)
			(end -2.2098 0.9398)
			(stroke
				(width 0.1524)
				(type default)
			)
			(layer "F.SilkS")
		)
		(fp_line
			(start -2.2098 -0.9398)
			(end 2.2098 -0.9398)
			(stroke
				(width 0.1524)
				(type default)
			)
			(layer "F.SilkS")
		)
		(fp_line
			(start 2.2098 -0.9398)
			(end 2.2098 0.9398)
			(stroke
				(width 0.1524)
				(type default)
			)
			(layer "F.SilkS")
		)
		(fp_line
			(start -1.700022 0.899922)
			(end -1.700022 -0.899922)
			(stroke
				(width 0.1)
				(type default)
			)
			(layer "F.Fab")
		)
		(fp_line
			(start 1.700022 0.899922)
			(end -1.700022 0.899922)
			(stroke
				(width 0.1)
				(type default)
			)
			(layer "F.Fab")
		)
		(fp_line
			(start -1.700022 -0.899922)
			(end 1.700022 -0.899922)
			(stroke
				(width 0.1)
				(type default)
			)
			(layer "F.Fab")
		)
		(fp_line
			(start 1.700022 -0.899922)
			(end 1.700022 0.899922)
			(stroke
				(width 0.1)
				(type default)
			)
			(layer "F.Fab")
		)
		(pad "1" smd rect
			(at -1.4732 0 90)
			(size 1.1684 1.5748)
			(layers "F.Cu" "F.Mask" "F.Paste")
			(net "P52V_HS")
		)
		(pad "2" smd rect
			(at 1.4732 0 90)
			(size 1.1684 1.5748)
			(layers "F.Cu" "F.Mask" "F.Paste")
			(net "GND")
		)
	)
	(footprint ""
		(layer "F.Cu")
		(at 199.987916 -66.956686 -90)
		(property "Reference" "R58"
			(at 0 0 270)
			(layer "F.SilkS")
			(hide yes)
			(effects
				(font
					(size 1.27 1.27)
				)
			)
		)
		(property "Value" ""
			(at 0 0 270)
			(layer "F.Fab")
			(effects
				(font
					(size 1.27 1.27)
				)
			)
		)
		(duplicate_pad_numbers_are_jumpers no)
		(fp_line
			(start -0.7874 0.4064)
			(end -0.7874 -0.4064)
			(stroke
				(width 0.1524)
				(type default)
			)
			(layer "F.SilkS")
		)
		(fp_line
			(start 0.7874 0.4064)
			(end -0.7874 0.4064)
			(stroke
				(width 0.1524)
				(type default)
			)
			(layer "F.SilkS")
		)
		(fp_line
			(start -0.7874 -0.4064)
			(end 0.7874 -0.4064)
			(stroke
				(width 0.1524)
				(type default)
			)
			(layer "F.SilkS")
		)
		(fp_line
			(start 0.7874 -0.4064)
			(end 0.7874 0.4064)
			(stroke
				(width 0.1524)
				(type default)
			)
			(layer "F.SilkS")
		)
		(fp_line
			(start -0.67945 0.3048)
			(end -0.67945 -0.305054)
			(stroke
				(width 0.1)
				(type default)
			)
			(layer "F.Fab")
		)
		(fp_line
			(start -0.12065 0.3048)
			(end -0.67945 0.3048)
			(stroke
				(width 0.1)
				(type default)
			)
			(layer "F.Fab")
		)
		(fp_line
			(start 0.120396 0.3048)
			(end 0.120396 0.2794)
			(stroke
				(width 0.1)
				(type default)
			)
			(layer "F.Fab")
		)
		(fp_line
			(start 0.67945 0.3048)
			(end 0.120396 0.3048)
			(stroke
				(width 0.1)
				(type default)
			)
			(layer "F.Fab")
		)
		(fp_line
			(start -0.12065 0.2794)
			(end -0.12065 0.3048)
			(stroke
				(width 0.1)
				(type default)
			)
			(layer "F.Fab")
		)
		(fp_line
			(start 0.120396 0.2794)
			(end -0.12065 0.2794)
			(stroke
				(width 0.1)
				(type default)
			)
			(layer "F.Fab")
		)
		(fp_line
			(start -0.12065 -0.2794)
			(end 0.12065 -0.2794)
			(stroke
				(width 0.1)
				(type default)
			)
			(layer "F.Fab")
		)
		(fp_line
			(start 0.12065 -0.2794)
			(end 0.12065 -0.3048)
			(stroke
				(width 0.1)
				(type default)
			)
			(layer "F.Fab")
		)
		(fp_line
			(start 0.12065 -0.3048)
			(end 0.67945 -0.3048)
			(stroke
				(width 0.1)
				(type default)
			)
			(layer "F.Fab")
		)
		(fp_line
			(start 0.67945 -0.3048)
			(end 0.67945 0.3048)
			(stroke
				(width 0.1)
				(type default)
			)
			(layer "F.Fab")
		)
		(fp_line
			(start -0.67945 -0.305054)
			(end -0.12065 -0.305054)
			(stroke
				(width 0.1)
				(type default)
			)
			(layer "F.Fab")
		)
		(fp_line
			(start -0.12065 -0.305054)
			(end -0.12065 -0.2794)
			(stroke
				(width 0.1)
				(type default)
			)
			(layer "F.Fab")
		)
		(pad "1" smd circle
			(at -0.40005 0 270)
			(size 0 0)
			(layers "F.Cu" "F.Mask" "F.Paste")
			(net "LED_D2_R1")
		)
		(pad "2" smd circle
			(at 0.40005 0 270)
			(size 0 0)
			(layers "F.Cu" "F.Mask" "F.Paste")
			(net "LED_D2_R2")
		)
	)
	(footprint ""
		(layer "F.Cu")
		(at 298.069 -28.321)
		(property "Reference" "R5887"
			(at 0 0 0)
			(layer "F.SilkS")
			(hide yes)
			(effects
				(font
					(size 1.27 1.27)
				)
			)
		)
		(property "Value" ""
			(at 0 0 0)
			(layer "F.Fab")
			(effects
				(font
					(size 1.27 1.27)
				)
			)
		)
		(duplicate_pad_numbers_are_jumpers no)
		(fp_line
			(start -0.7874 -0.4064)
			(end 0.7874 -0.4064)
			(stroke
				(width 0.1524)
				(type default)
			)
			(layer "F.SilkS")
		)
		(fp_line
			(start -0.7874 0.4064)
			(end -0.7874 -0.4064)
			(stroke
				(width 0.1524)
				(type default)
			)
			(layer "F.SilkS")
		)
		(fp_line
			(start 0.7874 -0.4064)
			(end 0.7874 0.4064)
			(stroke
				(width 0.1524)
				(type default)
			)
			(layer "F.SilkS")
		)
		(fp_line
			(start 0.7874 0.4064)
			(end -0.7874 0.4064)
			(stroke
				(width 0.1524)
				(type default)
			)
			(layer "F.SilkS")
		)
		(fp_line
			(start -0.67945 -0.305054)
			(end -0.12065 -0.305054)
			(stroke
				(width 0.1)
				(type default)
			)
			(layer "F.Fab")
		)
		(fp_line
			(start -0.67945 0.3048)
			(end -0.67945 -0.305054)
			(stroke
				(width 0.1)
				(type default)
			)
			(layer "F.Fab")
		)
		(fp_line
			(start -0.12065 -0.305054)
			(end -0.12065 -0.2794)
			(stroke
				(width 0.1)
				(type default)
			)
			(layer "F.Fab")
		)
		(fp_line
			(start -0.12065 -0.2794)
			(end 0.12065 -0.2794)
			(stroke
				(width 0.1)
				(type default)
			)
			(layer "F.Fab")
		)
		(fp_line
			(start -0.12065 0.2794)
			(end -0.12065 0.3048)
			(stroke
				(width 0.1)
				(type default)
			)
			(layer "F.Fab")
		)
		(fp_line
			(start -0.12065 0.3048)
			(end -0.67945 0.3048)
			(stroke
				(width 0.1)
				(type default)
			)
			(layer "F.Fab")
		)
		(fp_line
			(start 0.120396 0.2794)
			(end -0.12065 0.2794)
			(stroke
				(width 0.1)
				(type default)
			)
			(layer "F.Fab")
		)
		(fp_line
			(start 0.120396 0.3048)
			(end 0.120396 0.2794)
			(stroke
				(width 0.1)
				(type default)
			)
			(layer "F.Fab")
		)
		(fp_line
			(start 0.12065 -0.3048)
			(end 0.67945 -0.3048)
			(stroke
				(width 0.1)
				(type default)
			)
			(layer "F.Fab")
		)
		(fp_line
			(start 0.12065 -0.2794)
			(end 0.12065 -0.3048)
			(stroke
				(width 0.1)
				(type default)
			)
			(layer "F.Fab")
		)
		(fp_line
			(start 0.67945 -0.3048)
			(end 0.67945 0.3048)
			(stroke
				(width 0.1)
				(type default)
			)
			(layer "F.Fab")
		)
		(fp_line
			(start 0.67945 0.3048)
			(end 0.120396 0.3048)
			(stroke
				(width 0.1)
				(type default)
			)
			(layer "F.Fab")
		)
		(pad "1" smd circle
			(at -0.40005 0)
			(size 0 0)
			(layers "F.Cu" "F.Mask" "F.Paste")
			(net "FM_HSC_EN_FUSE")
		)
		(pad "2" smd circle
			(at 0.40005 0)
			(size 0 0)
			(layers "F.Cu" "F.Mask" "F.Paste")
			(net "GND")
		)
	)
)
